G04 ================== begin FILE IDENTIFICATION RECORD ==================*
G04 Layout Name:  15750-1.brd*
G04 Film Name:    TSMD*
G04 File Format:  Gerber RS274X*
G04 File Origin:  Cadence Allegro 16.5-S056*
G04 Origin Date:  Fri Dec 30 13:21:32 2016*
G04 *
G04 Layer:  VIA CLASS/PASTEMASK_TOP*
G04 Layer:  PIN/PASTEMASK_TOP*
G04 Layer:  PACKAGE GEOMETRY/PASTEMASK_TOP*
G04 Layer:  DRAWING FORMAT/LAYER_PCB_STORY*
G04 Layer:  DRAWING FORMAT/LAYER_PAST_T*
G04 Layer:  BOARD GEOMETRY/PANEL_OUTLINE*
G04 *
G04 Offset:    (0.00 0.00)*
G04 Mirror:    No*
G04 Mode:      Positive*
G04 Rotation:  0*
G04 FullContactRelief:  No*
G04 UndefLineWidth:     6.00*
G04 ================== end FILE IDENTIFICATION RECORD ====================*
%FSLAX35Y35*MOIN*%
%IR0*IPPOS*OFA0.00000B0.00000*MIA0B0*SFA1.00000B1.00000*%
%AMMACRO44*
4,1,40,.013,.017,
-.013,.017,
-.013695,.016939,
-.014368,.016759,
-.015,.016464,
-.015571,.016064,
-.016064,.015571,
-.016464,.015,
-.016759,.014368,
-.016939,.013695,
-.017,.013,
-.017,-.013,
-.016939,-.013695,
-.016759,-.014368,
-.016464,-.015,
-.016064,-.015571,
-.015571,-.016064,
-.015,-.016464,
-.014368,-.016759,
-.013695,-.016939,
-.013,-.017,
.013,-.017,
.013695,-.016939,
.014368,-.016759,
.015,-.016464,
.015571,-.016064,
.016064,-.015571,
.016464,-.015,
.016759,-.014368,
.016939,-.013695,
.017,-.013,
.017,.013,
.016939,.013695,
.016759,.014368,
.016464,.015,
.016064,.015571,
.015571,.016064,
.015,.016464,
.014368,.016759,
.013695,.016939,
.013,.017,
0.0*
%
%ADD44MACRO44*%
%AMMACRO23*
4,1,40,.017,-.013,
.017,.013,
.016939,.013695,
.016759,.014368,
.016464,.015,
.016064,.015571,
.015571,.016064,
.015,.016464,
.014368,.016759,
.013695,.016939,
.013,.017,
-.013,.017,
-.013695,.016939,
-.014368,.016759,
-.015,.016464,
-.015571,.016064,
-.016064,.015571,
-.016464,.015,
-.016759,.014368,
-.016939,.013695,
-.017,.013,
-.017,-.013,
-.016939,-.013695,
-.016759,-.014368,
-.016464,-.015,
-.016064,-.015571,
-.015571,-.016064,
-.015,-.016464,
-.014368,-.016759,
-.013695,-.016939,
-.013,-.017,
.013,-.017,
.013695,-.016939,
.014368,-.016759,
.015,-.016464,
.015571,-.016064,
.016064,-.015571,
.016464,-.015,
.016759,-.014368,
.016939,-.013695,
.017,-.013,
0.0*
%
%ADD23MACRO23*%
%AMMACRO41*
4,1,3,.025,.0125,
0.0,-.0125,
-.025,.0125,
.025,.0125,
0.0*
%
%ADD41MACRO41*%
%ADD42R,.102X.053*%
%ADD11C,.04*%
%ADD48R,.108X.047*%
%ADD13C,.028*%
%ADD10C,.086*%
%AMMACRO38*
4,1,40,.011,-.007,
.011,.007,
.010939,.007695,
.010759,.008368,
.010464,.009,
.010064,.009571,
.009571,.010064,
.009,.010464,
.008368,.010759,
.007695,.010939,
.007,.011,
-.007,.011,
-.007695,.010939,
-.008368,.010759,
-.009,.010464,
-.009571,.010064,
-.010064,.009571,
-.010464,.009,
-.010759,.008368,
-.010939,.007695,
-.011,.007,
-.011,-.007,
-.010939,-.007695,
-.010759,-.008368,
-.010464,-.009,
-.010064,-.009571,
-.009571,-.010064,
-.009,-.010464,
-.008368,-.010759,
-.007695,-.010939,
-.007,-.011,
.007,-.011,
.007695,-.010939,
.008368,-.010759,
.009,-.010464,
.009571,-.010064,
.010064,-.009571,
.010464,-.009,
.010759,-.008368,
.010939,-.007695,
.011,-.007,
0.0*
%
%ADD38MACRO38*%
%AMMACRO15*
4,1,40,.007,.011,
-.007,.011,
-.007695,.010939,
-.008368,.010759,
-.009,.010464,
-.009571,.010064,
-.010064,.009571,
-.010464,.009,
-.010759,.008368,
-.010939,.007695,
-.011,.007,
-.011,-.007,
-.010939,-.007695,
-.010759,-.008368,
-.010464,-.009,
-.010064,-.009571,
-.009571,-.010064,
-.009,-.010464,
-.008368,-.010759,
-.007695,-.010939,
-.007,-.011,
.007,-.011,
.007695,-.010939,
.008368,-.010759,
.009,-.010464,
.009571,-.010064,
.010064,-.009571,
.010464,-.009,
.010759,-.008368,
.010939,-.007695,
.011,-.007,
.011,.007,
.010939,.007695,
.010759,.008368,
.010464,.009,
.010064,.009571,
.009571,.010064,
.009,.010464,
.008368,.010759,
.007695,.010939,
.007,.011,
0.0*
%
%ADD15MACRO15*%
%AMMACRO21*
4,1,20,-.047,-.032,
-.047,-.0155,
-.074,-.0155,
-.074,-.0045,
-.049,-.0045,
-.049,.0045,
-.074,.0045,
-.074,.0155,
-.047,.0155,
-.047,.032,
.047,.032,
.047,.0155,
.074,.0155,
.074,.0045,
.049,.0045,
.049,-.0045,
.074,-.0045,
.074,-.0155,
.047,-.0155,
.047,-.032,
-.047,-.032,
0.0*
%
%ADD21MACRO21*%
%AMMACRO30*
4,1,40,-.012,.008,
-.012,-.008,
-.011939,-.008695,
-.011759,-.009368,
-.011464,-.01,
-.011064,-.010571,
-.010571,-.011064,
-.01,-.011464,
-.009368,-.011759,
-.008695,-.011939,
-.008,-.012,
.008,-.012,
.008695,-.011939,
.009368,-.011759,
.01,-.011464,
.010571,-.011064,
.011064,-.010571,
.011464,-.01,
.011759,-.009368,
.011939,-.008695,
.012,-.008,
.012,.008,
.011939,.008695,
.011759,.009368,
.011464,.01,
.011064,.010571,
.010571,.011064,
.01,.011464,
.009368,.011759,
.008695,.011939,
.008,.012,
-.008,.012,
-.008695,.011939,
-.009368,.011759,
-.01,.011464,
-.010571,.011064,
-.011064,.010571,
-.011464,.01,
-.011759,.009368,
-.011939,.008695,
-.012,.008,
0.0*
%
%ADD30MACRO30*%
%AMMACRO20*
4,1,40,.008,.012,
-.008,.012,
-.008695,.011939,
-.009368,.011759,
-.01,.011464,
-.010571,.011064,
-.011064,.010571,
-.011464,.01,
-.011759,.009368,
-.011939,.008695,
-.012,.008,
-.012,-.008,
-.011939,-.008695,
-.011759,-.009368,
-.011464,-.01,
-.011064,-.010571,
-.010571,-.011064,
-.01,-.011464,
-.009368,-.011759,
-.008695,-.011939,
-.008,-.012,
.008,-.012,
.008695,-.011939,
.009368,-.011759,
.01,-.011464,
.010571,-.011064,
.011064,-.010571,
.011464,-.01,
.011759,-.009368,
.011939,-.008695,
.012,-.008,
.012,.008,
.011939,.008695,
.011759,.009368,
.011464,.01,
.011064,.010571,
.010571,.011064,
.01,.011464,
.009368,.011759,
.008695,.011939,
.008,.012,
0.0*
%
%ADD20MACRO20*%
%AMMACRO49*
4,1,40,-.017,.013,
-.017,-.013,
-.016939,-.013695,
-.016759,-.014368,
-.016464,-.015,
-.016064,-.015571,
-.015571,-.016064,
-.015,-.016464,
-.014368,-.016759,
-.013695,-.016939,
-.013,-.017,
.013,-.017,
.013695,-.016939,
.014368,-.016759,
.015,-.016464,
.015571,-.016064,
.016064,-.015571,
.016464,-.015,
.016759,-.014368,
.016939,-.013695,
.017,-.013,
.017,.013,
.016939,.013695,
.016759,.014368,
.016464,.015,
.016064,.015571,
.015571,.016064,
.015,.016464,
.014368,.016759,
.013695,.016939,
.013,.017,
-.013,.017,
-.013695,.016939,
-.014368,.016759,
-.015,.016464,
-.015571,.016064,
-.016064,.015571,
-.016464,.015,
-.016759,.014368,
-.016939,.013695,
-.017,.013,
0.0*
%
%ADD49MACRO49*%
%AMMACRO39*
4,1,40,.011,-.007,
.011,.007,
.010939,.007695,
.010759,.008368,
.010464,.009,
.010064,.009571,
.009571,.010064,
.009,.010464,
.008368,.010759,
.007695,.010939,
.007,.011,
-.007,.011,
-.007695,.010939,
-.008368,.010759,
-.009,.010464,
-.009571,.010064,
-.010064,.009571,
-.010464,.009,
-.010759,.008368,
-.010939,.007695,
-.011,.007,
-.011,-.007,
-.010939,-.007695,
-.010759,-.008368,
-.010464,-.009,
-.010064,-.009571,
-.009571,-.010064,
-.009,-.010464,
-.008368,-.010759,
-.007695,-.010939,
-.007,-.011,
.007,-.011,
.007695,-.010939,
.008368,-.010759,
.009,-.010464,
.009571,-.010064,
.010064,-.009571,
.010464,-.009,
.010759,-.008368,
.010939,-.007695,
.011,-.007,
0.0*
%
%ADD39MACRO39*%
%AMMACRO16*
4,1,40,.007,.011,
-.007,.011,
-.007695,.010939,
-.008368,.010759,
-.009,.010464,
-.009571,.010064,
-.010064,.009571,
-.010464,.009,
-.010759,.008368,
-.010939,.007695,
-.011,.007,
-.011,-.007,
-.010939,-.007695,
-.010759,-.008368,
-.010464,-.009,
-.010064,-.009571,
-.009571,-.010064,
-.009,-.010464,
-.008368,-.010759,
-.007695,-.010939,
-.007,-.011,
.007,-.011,
.007695,-.010939,
.008368,-.010759,
.009,-.010464,
.009571,-.010064,
.010064,-.009571,
.010464,-.009,
.010759,-.008368,
.010939,-.007695,
.011,-.007,
.011,.007,
.010939,.007695,
.010759,.008368,
.010464,.009,
.010064,.009571,
.009571,.010064,
.009,.010464,
.008368,.010759,
.007695,.010939,
.007,.011,
0.0*
%
%ADD16MACRO16*%
%AMMACRO29*
4,1,40,-.012,.008,
-.012,-.008,
-.011939,-.008695,
-.011759,-.009368,
-.011464,-.01,
-.011064,-.010571,
-.010571,-.011064,
-.01,-.011464,
-.009368,-.011759,
-.008695,-.011939,
-.008,-.012,
.008,-.012,
.008695,-.011939,
.009368,-.011759,
.01,-.011464,
.010571,-.011064,
.011064,-.010571,
.011464,-.01,
.011759,-.009368,
.011939,-.008695,
.012,-.008,
.012,.008,
.011939,.008695,
.011759,.009368,
.011464,.01,
.011064,.010571,
.010571,.011064,
.01,.011464,
.009368,.011759,
.008695,.011939,
.008,.012,
-.008,.012,
-.008695,.011939,
-.009368,.011759,
-.01,.011464,
-.010571,.011064,
-.011064,.010571,
-.011464,.01,
-.011759,.009368,
-.011939,.008695,
-.012,.008,
0.0*
%
%ADD29MACRO29*%
%AMMACRO19*
4,1,40,.008,.012,
-.008,.012,
-.008695,.011939,
-.009368,.011759,
-.01,.011464,
-.010571,.011064,
-.011064,.010571,
-.011464,.01,
-.011759,.009368,
-.011939,.008695,
-.012,.008,
-.012,-.008,
-.011939,-.008695,
-.011759,-.009368,
-.011464,-.01,
-.011064,-.010571,
-.010571,-.011064,
-.01,-.011464,
-.009368,-.011759,
-.008695,-.011939,
-.008,-.012,
.008,-.012,
.008695,-.011939,
.009368,-.011759,
.01,-.011464,
.010571,-.011064,
.011064,-.010571,
.011464,-.01,
.011759,-.009368,
.011939,-.008695,
.012,-.008,
.012,.008,
.011939,.008695,
.011759,.009368,
.011464,.01,
.011064,.010571,
.010571,.011064,
.01,.011464,
.009368,.011759,
.008695,.011939,
.008,.012,
0.0*
%
%ADD19MACRO19*%
%AMMACRO50*
4,1,40,-.017,.013,
-.017,-.013,
-.016939,-.013695,
-.016759,-.014368,
-.016464,-.015,
-.016064,-.015571,
-.015571,-.016064,
-.015,-.016464,
-.014368,-.016759,
-.013695,-.016939,
-.013,-.017,
.013,-.017,
.013695,-.016939,
.014368,-.016759,
.015,-.016464,
.015571,-.016064,
.016064,-.015571,
.016464,-.015,
.016759,-.014368,
.016939,-.013695,
.017,-.013,
.017,.013,
.016939,.013695,
.016759,.014368,
.016464,.015,
.016064,.015571,
.015571,.016064,
.015,.016464,
.014368,.016759,
.013695,.016939,
.013,.017,
-.013,.017,
-.013695,.016939,
-.014368,.016759,
-.015,.016464,
-.015571,.016064,
-.016064,.015571,
-.016464,.015,
-.016759,.014368,
-.016939,.013695,
-.017,.013,
0.0*
%
%ADD50MACRO50*%
%AMMACRO40*
4,1,3,0.0,.0125,
.025,-.0125,
-.025,-.0125,
0.0,.0125,
0.0*
%
%ADD40MACRO40*%
%ADD33R,.06X.012*%
%ADD46R,.061X.012*%
%ADD28R,.012X.06*%
%ADD45R,.06X.014*%
%ADD37R,.044X.012*%
%ADD34R,.014X.06*%
%ADD17R,.012X.036*%
%ADD14R,.045X.055*%
%ADD51R,.016X.048*%
%ADD35R,.055X.045*%
%ADD47R,.095X.09*%
%AMMACRO31*
4,1,40,-.007,-.011,
.007,-.011,
.007695,-.010939,
.008368,-.010759,
.009,-.010464,
.009571,-.010064,
.010064,-.009571,
.010464,-.009,
.010759,-.008368,
.010939,-.007695,
.011,-.007,
.011,.007,
.010939,.007695,
.010759,.008368,
.010464,.009,
.010064,.009571,
.009571,.010064,
.009,.010464,
.008368,.010759,
.007695,.010939,
.007,.011,
-.007,.011,
-.007695,.010939,
-.008368,.010759,
-.009,.010464,
-.009571,.010064,
-.010064,.009571,
-.010464,.009,
-.010759,.008368,
-.010939,.007695,
-.011,.007,
-.011,-.007,
-.010939,-.007695,
-.010759,-.008368,
-.010464,-.009,
-.010064,-.009571,
-.009571,-.010064,
-.009,-.010464,
-.008368,-.010759,
-.007695,-.010939,
-.007,-.011,
0.0*
%
%ADD31MACRO31*%
%AMMACRO27*
4,1,40,-.008,-.012,
.008,-.012,
.008695,-.011939,
.009368,-.011759,
.01,-.011464,
.010571,-.011064,
.011064,-.010571,
.011464,-.01,
.011759,-.009368,
.011939,-.008695,
.012,-.008,
.012,.008,
.011939,.008695,
.011759,.009368,
.011464,.01,
.011064,.010571,
.010571,.011064,
.01,.011464,
.009368,.011759,
.008695,.011939,
.008,.012,
-.008,.012,
-.008695,.011939,
-.009368,.011759,
-.01,.011464,
-.010571,.011064,
-.011064,.010571,
-.011464,.01,
-.011759,.009368,
-.011939,.008695,
-.012,.008,
-.012,-.008,
-.011939,-.008695,
-.011759,-.009368,
-.011464,-.01,
-.011064,-.010571,
-.010571,-.011064,
-.01,-.011464,
-.009368,-.011759,
-.008695,-.011939,
-.008,-.012,
0.0*
%
%ADD27MACRO27*%
%AMMACRO12*
4,1,40,.012,-.008,
.012,.008,
.011939,.008695,
.011759,.009368,
.011464,.01,
.011064,.010571,
.010571,.011064,
.01,.011464,
.009368,.011759,
.008695,.011939,
.008,.012,
-.008,.012,
-.008695,.011939,
-.009368,.011759,
-.01,.011464,
-.010571,.011064,
-.011064,.010571,
-.011464,.01,
-.011759,.009368,
-.011939,.008695,
-.012,.008,
-.012,-.008,
-.011939,-.008695,
-.011759,-.009368,
-.011464,-.01,
-.011064,-.010571,
-.010571,-.011064,
-.01,-.011464,
-.009368,-.011759,
-.008695,-.011939,
-.008,-.012,
.008,-.012,
.008695,-.011939,
.009368,-.011759,
.01,-.011464,
.010571,-.011064,
.011064,-.010571,
.011464,-.01,
.011759,-.009368,
.011939,-.008695,
.012,-.008,
0.0*
%
%ADD12MACRO12*%
%AMMACRO24*
4,1,40,-.011,.007,
-.011,-.007,
-.010939,-.007695,
-.010759,-.008368,
-.010464,-.009,
-.010064,-.009571,
-.009571,-.010064,
-.009,-.010464,
-.008368,-.010759,
-.007695,-.010939,
-.007,-.011,
.007,-.011,
.007695,-.010939,
.008368,-.010759,
.009,-.010464,
.009571,-.010064,
.010064,-.009571,
.010464,-.009,
.010759,-.008368,
.010939,-.007695,
.011,-.007,
.011,.007,
.010939,.007695,
.010759,.008368,
.010464,.009,
.010064,.009571,
.009571,.010064,
.009,.010464,
.008368,.010759,
.007695,.010939,
.007,.011,
-.007,.011,
-.007695,.010939,
-.008368,.010759,
-.009,.010464,
-.009571,.010064,
-.010064,.009571,
-.010464,.009,
-.010759,.008368,
-.010939,.007695,
-.011,.007,
0.0*
%
%ADD24MACRO24*%
%AMMACRO43*
4,1,40,.013,.017,
-.013,.017,
-.013695,.016939,
-.014368,.016759,
-.015,.016464,
-.015571,.016064,
-.016064,.015571,
-.016464,.015,
-.016759,.014368,
-.016939,.013695,
-.017,.013,
-.017,-.013,
-.016939,-.013695,
-.016759,-.014368,
-.016464,-.015,
-.016064,-.015571,
-.015571,-.016064,
-.015,-.016464,
-.014368,-.016759,
-.013695,-.016939,
-.013,-.017,
.013,-.017,
.013695,-.016939,
.014368,-.016759,
.015,-.016464,
.015571,-.016064,
.016064,-.015571,
.016464,-.015,
.016759,-.014368,
.016939,-.013695,
.017,-.013,
.017,.013,
.016939,.013695,
.016759,.014368,
.016464,.015,
.016064,.015571,
.015571,.016064,
.015,.016464,
.014368,.016759,
.013695,.016939,
.013,.017,
0.0*
%
%ADD43MACRO43*%
%AMMACRO22*
4,1,40,.017,-.013,
.017,.013,
.016939,.013695,
.016759,.014368,
.016464,.015,
.016064,.015571,
.015571,.016064,
.015,.016464,
.014368,.016759,
.013695,.016939,
.013,.017,
-.013,.017,
-.013695,.016939,
-.014368,.016759,
-.015,.016464,
-.015571,.016064,
-.016064,.015571,
-.016464,.015,
-.016759,.014368,
-.016939,.013695,
-.017,.013,
-.017,-.013,
-.016939,-.013695,
-.016759,-.014368,
-.016464,-.015,
-.016064,-.015571,
-.015571,-.016064,
-.015,-.016464,
-.014368,-.016759,
-.013695,-.016939,
-.013,-.017,
.013,-.017,
.013695,-.016939,
.014368,-.016759,
.015,-.016464,
.015571,-.016064,
.016064,-.015571,
.016464,-.015,
.016759,-.014368,
.016939,-.013695,
.017,-.013,
0.0*
%
%ADD22MACRO22*%
%AMMACRO36*
4,1,20,-.0635,.1075,
-.049,.1075,
-.049,.118,
-.0395,.118,
-.0395,.1075,
.0395,.1075,
.0395,.118,
.049,.118,
.049,.1075,
.0635,.1075,
.0635,-.1075,
.049,-.1075,
.049,-.118,
.0395,-.118,
.0395,-.1075,
-.0395,-.1075,
-.0395,-.118,
-.049,-.118,
-.049,-.1075,
-.0635,-.1075,
-.0635,.1075,
0.0*
%
%ADD36MACRO36*%
%AMMACRO32*
4,1,40,-.007,-.011,
.007,-.011,
.007695,-.010939,
.008368,-.010759,
.009,-.010464,
.009571,-.010064,
.010064,-.009571,
.010464,-.009,
.010759,-.008368,
.010939,-.007695,
.011,-.007,
.011,.007,
.010939,.007695,
.010759,.008368,
.010464,.009,
.010064,.009571,
.009571,.010064,
.009,.010464,
.008368,.010759,
.007695,.010939,
.007,.011,
-.007,.011,
-.007695,.010939,
-.008368,.010759,
-.009,.010464,
-.009571,.010064,
-.010064,.009571,
-.010464,.009,
-.010759,.008368,
-.010939,.007695,
-.011,.007,
-.011,-.007,
-.010939,-.007695,
-.010759,-.008368,
-.010464,-.009,
-.010064,-.009571,
-.009571,-.010064,
-.009,-.010464,
-.008368,-.010759,
-.007695,-.010939,
-.007,-.011,
0.0*
%
%ADD32MACRO32*%
%AMMACRO26*
4,1,40,-.008,-.012,
.008,-.012,
.008695,-.011939,
.009368,-.011759,
.01,-.011464,
.010571,-.011064,
.011064,-.010571,
.011464,-.01,
.011759,-.009368,
.011939,-.008695,
.012,-.008,
.012,.008,
.011939,.008695,
.011759,.009368,
.011464,.01,
.011064,.010571,
.010571,.011064,
.01,.011464,
.009368,.011759,
.008695,.011939,
.008,.012,
-.008,.012,
-.008695,.011939,
-.009368,.011759,
-.01,.011464,
-.010571,.011064,
-.011064,.010571,
-.011464,.01,
-.011759,.009368,
-.011939,.008695,
-.012,.008,
-.012,-.008,
-.011939,-.008695,
-.011759,-.009368,
-.011464,-.01,
-.011064,-.010571,
-.010571,-.011064,
-.01,-.011464,
-.009368,-.011759,
-.008695,-.011939,
-.008,-.012,
0.0*
%
%ADD26MACRO26*%
%AMMACRO18*
4,1,40,.012,-.008,
.012,.008,
.011939,.008695,
.011759,.009368,
.011464,.01,
.011064,.010571,
.010571,.011064,
.01,.011464,
.009368,.011759,
.008695,.011939,
.008,.012,
-.008,.012,
-.008695,.011939,
-.009368,.011759,
-.01,.011464,
-.010571,.011064,
-.011064,.010571,
-.011464,.01,
-.011759,.009368,
-.011939,.008695,
-.012,.008,
-.012,-.008,
-.011939,-.008695,
-.011759,-.009368,
-.011464,-.01,
-.011064,-.010571,
-.010571,-.011064,
-.01,-.011464,
-.009368,-.011759,
-.008695,-.011939,
-.008,-.012,
.008,-.012,
.008695,-.011939,
.009368,-.011759,
.01,-.011464,
.010571,-.011064,
.011064,-.010571,
.011464,-.01,
.011759,-.009368,
.011939,-.008695,
.012,-.008,
0.0*
%
%ADD18MACRO18*%
%AMMACRO25*
4,1,40,-.011,.007,
-.011,-.007,
-.010939,-.007695,
-.010759,-.008368,
-.010464,-.009,
-.010064,-.009571,
-.009571,-.010064,
-.009,-.010464,
-.008368,-.010759,
-.007695,-.010939,
-.007,-.011,
.007,-.011,
.007695,-.010939,
.008368,-.010759,
.009,-.010464,
.009571,-.010064,
.010064,-.009571,
.010464,-.009,
.010759,-.008368,
.010939,-.007695,
.011,-.007,
.011,.007,
.010939,.007695,
.010759,.008368,
.010464,.009,
.010064,.009571,
.009571,.010064,
.009,.010464,
.008368,.010759,
.007695,.010939,
.007,.011,
-.007,.011,
-.007695,.010939,
-.008368,.010759,
-.009,.010464,
-.009571,.010064,
-.010064,.009571,
-.010464,.009,
-.010759,.008368,
-.010939,.007695,
-.011,.007,
0.0*
%
%ADD25MACRO25*%
%ADD52C,.02*%
%ADD53C,.006*%
G75*
%LPD*%
G75*
G54D10*
X26087Y-114844D03*
X26435Y373984D03*
X175335Y62719D03*
Y189062D03*
X547104Y69007D03*
Y195351D03*
X696192Y373984D03*
G54D20*
X63000Y299889D03*
X103000Y280700D03*
X100500Y338889D03*
X109500Y283200D03*
X130000Y291700D03*
X203600Y296200D03*
X290000Y159700D03*
G54D11*
X22401Y341025D03*
X291000Y22500D03*
X316610Y341025D03*
G54D12*
X56200Y325189D03*
X67200Y302689D03*
X207300Y300200D03*
X233700Y67000D03*
Y75000D03*
Y71000D03*
Y122000D03*
Y126000D03*
Y138500D03*
Y130000D03*
Y134500D03*
Y175500D03*
Y183500D03*
Y179500D03*
Y238500D03*
Y243000D03*
Y230500D03*
Y234500D03*
Y247000D03*
G54D30*
X103800Y310000D03*
G54D21*
X71500Y315689D03*
G54D22*
X58000Y320489D03*
X169500Y336300D03*
X196000Y341300D03*
G54D31*
X100200Y317000D03*
Y321000D03*
X298200Y249000D03*
G54D40*
X185811Y298150D03*
G54D13*
X53500Y320689D03*
X71000Y294189D03*
X66750Y289689D03*
X59000Y304189D03*
X68000Y339189D03*
X58000Y337439D03*
X77500Y338000D03*
X95000Y289000D03*
X94500Y303100D03*
X96500Y332500D03*
X117913Y287300D03*
X122500Y285500D03*
X110500Y306000D03*
X123500Y304700D03*
X128500Y304500D03*
X162311Y298500D03*
X194811Y303500D03*
X207500Y296250D03*
X258000Y160500D03*
X299500Y144900D03*
X298500Y254000D03*
G54D32*
X96800Y317000D03*
Y321000D03*
X294800Y249000D03*
G54D14*
X58200Y331189D03*
X65800D03*
X76700Y285689D03*
X84300D03*
X76700Y293689D03*
X84300D03*
X76700Y301689D03*
X84300D03*
X76700Y331189D03*
X84300D03*
X255200Y296000D03*
Y304000D03*
X262800Y296000D03*
Y304000D03*
G54D50*
X297000Y123800D03*
G54D41*
X185811Y300850D03*
G54D23*
X58000Y314889D03*
X169500Y330700D03*
X196000Y335700D03*
G54D24*
X62000Y337489D03*
X95000Y280800D03*
X99000D03*
X114500Y281800D03*
X119000Y280300D03*
Y308300D03*
X115000D03*
X123500D03*
X127500D03*
X168311Y298300D03*
X199811Y296300D03*
X296000Y132300D03*
Y139800D03*
G54D51*
X295440Y162250D03*
X298000D03*
X300560D03*
Y168750D03*
X295440D03*
G54D33*
X123100Y294015D03*
Y292045D03*
X113900D03*
Y294015D03*
X123100Y297955D03*
Y295985D03*
X113900D03*
Y297955D03*
G54D15*
X63300Y294189D03*
X67300Y298689D03*
X70800Y345000D03*
X96800Y325000D03*
X192111Y299500D03*
X204111Y304000D03*
X294800Y245000D03*
G54D42*
X206943Y324000D03*
X232057D03*
G54D52*
G01X-176139Y-183003D02*
G02I-12000J0D01*
G01X-181289D02*
G02I-6850J0D01*
G01X-172139D02*
X-204139D01*
G01X-188139Y-199003D02*
Y-167003D01*
G01X-172139Y-199003D02*
Y-279003D01*
G01D02*
X1178561D01*
G01X-172139Y-234503D02*
X1178561D01*
G01X-172139Y-199003D02*
X1178561D01*
G01X391061D02*
Y-279003D01*
G01X528561Y-199003D02*
Y-279003D01*
G01X643561Y-199003D02*
Y-279003D01*
G01X811061Y-199003D02*
Y-279003D01*
G01X981061Y-199003D02*
Y-279003D01*
G01X1178561Y-199003D02*
Y-279003D01*
G01X1210561Y-183003D02*
X1178561D01*
G01X1206561D02*
G02I-12000J0D01*
G01X1201411D02*
G02I-6850J0D01*
G01X1194561Y-199003D02*
Y-167003D01*
G54D25*
X62000Y340889D03*
X95000Y284200D03*
X99000D03*
X114500Y285200D03*
X119000Y283700D03*
Y311700D03*
X115000D03*
X123500D03*
X127500D03*
X168311Y301700D03*
X199811Y299700D03*
X296000Y135700D03*
Y143200D03*
G54D43*
X208200Y292000D03*
G54D34*
X107325Y320089D03*
X109880D03*
X112440D03*
X115000D03*
X117560D03*
X120120D03*
X122675D03*
Y342289D03*
X120120D03*
X117560D03*
X115000D03*
X112440D03*
X109880D03*
X107325D03*
G54D16*
X66700Y294189D03*
X70700Y298689D03*
X74200Y345000D03*
X100200Y325000D03*
X195511Y299500D03*
X207511Y304000D03*
X298200Y245000D03*
G54D53*
G01X-148956Y-251503D02*
Y-269003D01*
X-140222D01*
G01X-127089Y-257337D02*
Y-269003D01*
G01Y-252670D02*
X-127526Y-252378D01*
Y-251795D01*
X-127089Y-251503D01*
X-126652Y-251795D01*
Y-252378D01*
X-127089Y-252670D01*
G01X-112646Y-273378D02*
X-111117Y-274545D01*
X-109371Y-274836D01*
X-107843Y-274545D01*
X-106532Y-273087D01*
X-105659Y-271045D01*
Y-257337D01*
G01Y-259670D02*
X-106532Y-258503D01*
X-107843Y-257628D01*
X-109371Y-257337D01*
X-111117Y-257920D01*
X-112209Y-259086D01*
X-113083Y-261128D01*
X-113519Y-263170D01*
X-113301Y-264920D01*
X-112427Y-266962D01*
X-111117Y-268420D01*
X-109371Y-269003D01*
X-108061Y-268711D01*
X-106532Y-267545D01*
X-105659Y-266379D01*
G01X-95801Y-269003D02*
Y-251503D01*
G01Y-259961D02*
X-94709Y-258503D01*
X-93617Y-257628D01*
X-91871Y-257337D01*
X-90561Y-257628D01*
X-89032Y-258795D01*
X-88377Y-260545D01*
Y-269003D01*
G01X-74589Y-251503D02*
Y-269003D01*
G01X-77646Y-257337D02*
X-71532D01*
G01X-60801Y-269003D02*
Y-257337D01*
G01Y-260253D02*
X-59927Y-258795D01*
X-58617Y-257628D01*
X-56871Y-257337D01*
X-55343Y-257628D01*
X-54032Y-258795D01*
X-53377Y-260836D01*
Y-269003D01*
G01X-39589Y-257337D02*
Y-269003D01*
G01Y-252670D02*
X-40026Y-252378D01*
Y-251795D01*
X-39589Y-251503D01*
X-39152Y-251795D01*
Y-252378D01*
X-39589Y-252670D01*
G01X-25801Y-269003D02*
Y-257337D01*
G01Y-260253D02*
X-24927Y-258795D01*
X-23617Y-257628D01*
X-21871Y-257337D01*
X-20343Y-257628D01*
X-19032Y-258795D01*
X-18377Y-260836D01*
Y-269003D01*
G01X-7646Y-273378D02*
X-6117Y-274545D01*
X-4371Y-274836D01*
X-2843Y-274545D01*
X-1532Y-273087D01*
X-659Y-271045D01*
Y-257337D01*
G01Y-259670D02*
X-1532Y-258503D01*
X-2843Y-257628D01*
X-4371Y-257337D01*
X-6117Y-257920D01*
X-7209Y-259086D01*
X-8083Y-261128D01*
X-8519Y-263170D01*
X-8301Y-264920D01*
X-7427Y-266962D01*
X-6117Y-268420D01*
X-4371Y-269003D01*
X-3061Y-268711D01*
X-1532Y-267545D01*
X-659Y-266379D01*
G01X26044Y-269003D02*
Y-251503D01*
X31284D01*
X33031Y-252378D01*
X34341Y-254420D01*
X34778Y-256753D01*
X34341Y-259086D01*
X33249Y-260836D01*
X31284Y-261712D01*
X26044D01*
G01X42452Y-251503D02*
X47911Y-269003D01*
X53370Y-251503D01*
G01X65411D02*
Y-269003D01*
G01X60389Y-251503D02*
X70433D01*
G01X94734Y-269003D02*
Y-251503D01*
X100411Y-266086D01*
X106088Y-251503D01*
Y-269003D01*
G01X117911Y-269586D02*
X117474Y-269295D01*
Y-268711D01*
X117911Y-268420D01*
X118348Y-268711D01*
Y-269295D01*
X117911Y-269586D01*
G01X131263Y-254420D02*
X132573Y-252670D01*
X134101Y-251795D01*
X135848Y-251503D01*
X138031Y-252086D01*
X139559Y-253545D01*
X139996Y-255294D01*
X139778Y-257045D01*
X138904Y-258503D01*
X134538Y-261420D01*
X132573Y-263461D01*
X131263Y-266379D01*
X130826Y-269003D01*
X139996D01*
G01X164952D02*
X170411Y-251503D01*
X175870Y-269003D01*
G01X173904Y-262878D02*
X166917D01*
G01X191841Y-251503D02*
Y-269003D01*
G01Y-266379D02*
X190968Y-267837D01*
X189657Y-268711D01*
X188129Y-269003D01*
X186383Y-268420D01*
X185073Y-266962D01*
X184199Y-265212D01*
X183981Y-263170D01*
X184199Y-261128D01*
X185073Y-259378D01*
X186383Y-257920D01*
X188129Y-257337D01*
X189657Y-257628D01*
X190749Y-258212D01*
X191841Y-259378D01*
G01X209341Y-269003D02*
Y-257337D01*
G01Y-259378D02*
X208468Y-258212D01*
X207157Y-257628D01*
X205629Y-257337D01*
X204101Y-257920D01*
X202791Y-259086D01*
X201917Y-260836D01*
X201481Y-263170D01*
X201917Y-265503D01*
X202791Y-267253D01*
X204101Y-268420D01*
X205629Y-269003D01*
X207157Y-268711D01*
X208468Y-267837D01*
X209341Y-266670D01*
G01X218981Y-274836D02*
Y-257337D01*
G01Y-259961D02*
X220073Y-258503D01*
X221164Y-257628D01*
X222911Y-257337D01*
X224439Y-257628D01*
X225968Y-259086D01*
X226623Y-261128D01*
X226841Y-263170D01*
X226623Y-265212D01*
X225968Y-267253D01*
X224657Y-268420D01*
X222911Y-269003D01*
X221383Y-268711D01*
X219854Y-267837D01*
X218981Y-266670D01*
G01X240411Y-251503D02*
Y-269003D01*
G01X237354Y-257337D02*
X243468D01*
G01X257911Y-269003D02*
X256601Y-268711D01*
X255291Y-267545D01*
X254417Y-265503D01*
X253981Y-263170D01*
X254417Y-260836D01*
X255291Y-258795D01*
X256601Y-257628D01*
X257911Y-257337D01*
X259221Y-257628D01*
X260531Y-258795D01*
X261404Y-260836D01*
X261623Y-263170D01*
X261404Y-265503D01*
X260531Y-267545D01*
X259221Y-268711D01*
X257911Y-269003D01*
G01X272354D02*
Y-257337D01*
G01Y-259670D02*
X273446Y-258503D01*
X274538Y-257628D01*
X276066Y-257337D01*
X277157Y-257628D01*
X278468Y-258503D01*
G01X315214Y-252962D02*
X313904Y-252086D01*
X312376Y-251503D01*
X310629D01*
X308664Y-252378D01*
X307136Y-253836D01*
X306044Y-255587D01*
X305171Y-258503D01*
X304952Y-261128D01*
X305389Y-263753D01*
X306044Y-265503D01*
X307354Y-267253D01*
X308883Y-268420D01*
X310411Y-269003D01*
X311939D01*
X313468Y-268420D01*
X314778Y-267545D01*
X315870Y-266379D01*
G01X331841Y-269003D02*
Y-257337D01*
G01Y-259378D02*
X330968Y-258212D01*
X329657Y-257628D01*
X328129Y-257337D01*
X326601Y-257920D01*
X325291Y-259086D01*
X324417Y-260836D01*
X323981Y-263170D01*
X324417Y-265503D01*
X325291Y-267253D01*
X326601Y-268420D01*
X328129Y-269003D01*
X329657Y-268711D01*
X330968Y-267837D01*
X331841Y-266670D01*
G01X342354Y-269003D02*
Y-257337D01*
G01Y-259670D02*
X343446Y-258503D01*
X344538Y-257628D01*
X346066Y-257337D01*
X347157Y-257628D01*
X348468Y-258503D01*
G01X366841Y-251503D02*
Y-269003D01*
G01Y-266379D02*
X365968Y-267837D01*
X364657Y-268711D01*
X363129Y-269003D01*
X361383Y-268420D01*
X360073Y-266962D01*
X359199Y-265212D01*
X358981Y-263170D01*
X359199Y-261128D01*
X360073Y-259378D01*
X361383Y-257920D01*
X363129Y-257337D01*
X364657Y-257628D01*
X365749Y-258212D01*
X366841Y-259378D01*
G01X-1Y-113228D02*
Y-117165D01*
G03X7873Y-125039I7874J0D01*
G01X714566D01*
G03X722440Y-117165I0J7874D01*
G01Y-113228D01*
G01X1968Y40473D02*
X9842D01*
G02X11811Y38504I0J-1969D01*
G01Y-16772D01*
G02X9842Y-18740I-1969J1D01*
G01X1968D01*
G03X0Y-20709I0J-1968D01*
G01Y-97480D01*
G03X7874Y-105354I7874J0D01*
G01X341535D01*
G03X349409Y-97480I0J7874D01*
G01Y-15748D01*
G03X341535Y-7874I-7874J0D01*
G01X141338D01*
G02X133464Y0I0J7874D01*
G01Y250197D01*
G03X125590Y258071I-7874J0D01*
G01X1968D01*
G03X0Y256102I0J-1968D01*
G01Y236673D01*
G03X1968Y234705I1968J0D01*
G01X28346D01*
G02X30315Y232736I0J-1969D01*
G01Y216004D01*
G02X28346Y214036I-1968J0D01*
G01X23228D01*
G03X21259Y212067I0J-1969D01*
G01Y86752D01*
G03X23228Y84784I1969J1D01*
G01X28346D01*
G02X30315Y82815I0J-1969D01*
G01Y66083D01*
G02X28346Y64114I-1969J0D01*
G01X1968D01*
G03X0Y62146I0J-1968D01*
G01Y42441D01*
G03X1968Y40473I1968J0D01*
G01X-1Y-113228D02*
X13591D01*
G01X347441Y217598D02*
X339567D01*
G02X337598Y219567I0J1969D01*
G01Y274843D01*
G02X339567Y276811I1969J-1D01*
G01X347441D01*
G03X349409Y278780I0J1968D01*
G01Y355551D01*
G03X341535Y363425I-7874J0D01*
G01X7874D01*
G03X0Y355551I0J-7874D01*
G01Y273819D01*
G03X7874Y265945I7874J0D01*
G01X208071D01*
G02X215945Y258071I0J-7874D01*
G01Y7874D01*
G03X223819Y0I7874J0D01*
G01X347441D01*
G03X349409Y1969I0J1968D01*
G01Y21398D01*
G03X347441Y23366I-1968J0D01*
G01X321063D01*
G02X319094Y25335I0J1969D01*
G01Y42067D01*
G02X321063Y44035I1969J-1D01*
G01X326181D01*
G03X328150Y46004I0J1969D01*
G01Y171319D01*
G03X326181Y173287I-1968J0D01*
G01X321063D01*
G02X319094Y175256I0J1969D01*
G01Y191988D01*
G02X321063Y193957I1969J0D01*
G01X347441D01*
G03X349409Y195925I0J1968D01*
G01Y215630D01*
G03X347441Y217598I-1968J0D01*
G01X245745Y383110D02*
X7874D01*
G03X0Y375236I0J-7874D01*
G01Y371299D01*
G01D02*
X13591D01*
G01Y-113228D02*
G03Y-105354I0J3937D01*
G01Y258071D02*
G03Y265945I0J3937D01*
G01Y363425D02*
G03Y371299I0J3937D01*
G01X38787Y-113228D02*
X237000D01*
G01X38787Y-105354D02*
G03Y-113228I1J-3937D01*
G01Y265945D02*
G03Y258071I1J-3937D01*
G01X237000Y371299D02*
X38787D01*
G01D02*
G03Y363425I1J-3937D01*
G01X68484Y-224003D02*
Y-206503D01*
X74161Y-221086D01*
X79838Y-206503D01*
Y-224003D01*
G01X91661D02*
X90351Y-223711D01*
X89041Y-222545D01*
X88167Y-220503D01*
X87731Y-218170D01*
X88167Y-215836D01*
X89041Y-213795D01*
X90351Y-212628D01*
X91661Y-212337D01*
X92971Y-212628D01*
X94281Y-213795D01*
X95154Y-215836D01*
X95373Y-218170D01*
X95154Y-220503D01*
X94281Y-222545D01*
X92971Y-223711D01*
X91661Y-224003D01*
G01X113091Y-206503D02*
Y-224003D01*
G01Y-221379D02*
X112218Y-222837D01*
X110907Y-223711D01*
X109379Y-224003D01*
X107633Y-223420D01*
X106323Y-221962D01*
X105449Y-220212D01*
X105231Y-218170D01*
X105449Y-216128D01*
X106323Y-214378D01*
X107633Y-212920D01*
X109379Y-212337D01*
X110907Y-212628D01*
X111999Y-213212D01*
X113091Y-214378D01*
G01X123386Y-216128D02*
X130373D01*
X129718Y-214086D01*
X128626Y-212920D01*
X127098Y-212337D01*
X125569Y-212628D01*
X124259Y-213503D01*
X123386Y-215545D01*
X122949Y-217295D01*
Y-219045D01*
X123386Y-220795D01*
X124478Y-222545D01*
X125788Y-223711D01*
X127316Y-224003D01*
X128844Y-223420D01*
X130373Y-221670D01*
G01X144161Y-224003D02*
Y-206503D01*
G01X141338Y116437D02*
G03X133464I-3937J0D01*
G01Y141634D02*
G03X141338I3937J0D01*
G01Y0D02*
Y116437D01*
G01X162106Y0D02*
X141337D01*
G01X141338Y141634D02*
Y258071D01*
G01D02*
X162106D01*
G01Y-7874D02*
G03Y0I0J3937D01*
G01X179626Y62719D02*
G03X171044I-4291J0D01*
G03X179626I4291J0D01*
G01Y189063D02*
G03X171044Y189062I-4291J0D01*
G03X179626Y189063I4291J1D01*
G01X162106Y258071D02*
G03Y265945I0J3937D01*
G01X187302Y0D02*
G03Y-7874I1J-3937D01*
G01X208071Y0D02*
X187302D01*
G01Y265945D02*
G03Y258071I1J-3937D01*
G01D02*
X208071D01*
G01X207913Y0D02*
X208071D01*
G01Y116437D02*
Y0D01*
G01X215945Y116437D02*
G03X208071I-3937J0D01*
G01Y141634D02*
G03X215945I3937J0D01*
G01X208071Y258071D02*
Y141634D01*
G01X237000Y-113228D02*
G03Y-105354I0J3937D01*
G01Y363425D02*
G03Y371299I0J3937D01*
G01X245745Y383110D02*
G03X253619I3937J0D01*
G01X722440Y371299D02*
Y375236D01*
G03X714566Y383110I-7874J0D01*
G01X253619D01*
G01X262196Y-113228D02*
X460244D01*
G01X262196Y-105354D02*
G03Y-113228I0J-3937D01*
G01Y371299D02*
X460244D01*
G01X262196D02*
G03Y363425I0J-3937D01*
G01X310621Y-7874D02*
G03Y0I0J3937D01*
G01X335817D02*
G03Y-7874I1J-3937D01*
G01X353346Y-47481D02*
G03X349409Y-51418I0J-3937D01*
G01Y-20709D02*
G03X353346Y-24646I3937J0D01*
G01Y282717D02*
G03X349409Y278780I0J-3937D01*
G01Y309489D02*
G03X353346Y305552I3937J0D01*
G01Y-47481D02*
X369094D01*
G01X373031Y-51418D02*
G03X369094Y-47481I-3937J0D01*
G01X353346Y-24646D02*
X369094D01*
G01D02*
G03X373031Y-20709I0J3937D01*
G01X353346Y282717D02*
X369094D01*
G01X373031Y278780D02*
G03X369094Y282717I-3937J0D01*
G01X353346Y305552D02*
X369094D01*
G01D02*
G03X373031Y309489I0J3937D01*
G01X374999Y40473D02*
X382873D01*
G02X384842Y38504I0J-1969D01*
G01Y-16772D01*
G02X382873Y-18740I-1969J1D01*
G01X374999D01*
G03X373031Y-20709I0J-1968D01*
G01Y-97480D01*
G03X380905Y-105354I7874J0D01*
G01X714566D01*
G03X722440Y-97480I0J7874D01*
G01Y-15748D01*
G03X714566Y-7874I-7874J0D01*
G01X514369D01*
G02X506495Y0I0J7874D01*
G01Y250197D01*
G03X498621Y258071I-7874J0D01*
G01X374999D01*
G03X373031Y256102I0J-1968D01*
G01Y236673D01*
G03X374999Y234705I1968J0D01*
G01X401377D01*
G02X403346Y232736I0J-1969D01*
G01Y216004D01*
G02X401377Y214036I-1968J0D01*
G01X396259D01*
G03X394290Y212067I0J-1969D01*
G01Y86752D01*
G03X396259Y84784I1969J1D01*
G01X401377D01*
G02X403346Y82815I0J-1969D01*
G01Y66083D01*
G02X401377Y64114I-1969J0D01*
G01X374999D01*
G03X373031Y62146I0J-1968D01*
G01Y42441D01*
G03X374999Y40473I1968J0D01*
G01X720472Y217598D02*
X712598D01*
G02X710629Y219567I0J1969D01*
G01Y274843D01*
G02X712598Y276811I1969J-1D01*
G01X720472D01*
G03X722440Y278780I0J1968D01*
G01Y355551D01*
G03X714566Y363425I-7874J0D01*
G01X380905D01*
G03X373031Y355551I0J-7874D01*
G01Y273819D01*
G03X380905Y265945I7874J0D01*
G01X581102D01*
G02X588976Y258071I0J-7874D01*
G01Y7874D01*
G03X596850Y0I7874J0D01*
G01X720472D01*
G03X722440Y1969I0J1968D01*
G01Y21398D01*
G03X720472Y23366I-1968J0D01*
G01X694094D01*
G02X692125Y25335I0J1969D01*
G01Y42067D01*
G02X694094Y44035I1969J-1D01*
G01X699212D01*
G03X701181Y46004I0J1969D01*
G01Y171319D01*
G03X699212Y173287I-1969J-1D01*
G01X694094D01*
G02X692125Y175256I0J1969D01*
G01Y191988D01*
G02X694094Y193957I1969J0D01*
G01X720472D01*
G03X722440Y195925I0J1968D01*
G01Y215630D01*
G03X720472Y217598I-1968J0D01*
G01X386622Y258071D02*
G03Y265945I0J3937D01*
G01X424761Y-269003D02*
Y-251503D01*
X422141Y-255003D01*
G01Y-269003D02*
X427381D01*
G01X437458Y-266379D02*
X438767Y-267837D01*
X440296Y-268711D01*
X442261Y-269003D01*
X444226Y-268420D01*
X445754Y-267253D01*
X446846Y-265212D01*
X447064Y-262878D01*
X446628Y-260545D01*
X445536Y-259086D01*
X444007Y-257920D01*
X442479Y-257628D01*
X440951Y-257920D01*
X438986Y-259086D01*
X439641Y-251503D01*
X445536D01*
G01X459324Y-269003D02*
X459761Y-265212D01*
X460416Y-262003D01*
X461289Y-259086D01*
X462381Y-255878D01*
X464128Y-251503D01*
X455394D01*
G01X472458Y-266379D02*
X473767Y-267837D01*
X475296Y-268711D01*
X477261Y-269003D01*
X479226Y-268420D01*
X480754Y-267253D01*
X481846Y-265212D01*
X482064Y-262878D01*
X481628Y-260545D01*
X480536Y-259086D01*
X479007Y-257920D01*
X477479Y-257628D01*
X475951Y-257920D01*
X473986Y-259086D01*
X474641Y-251503D01*
X480536D01*
G01X494761D02*
X493014Y-252086D01*
X491704Y-253545D01*
X490831Y-255294D01*
X490176Y-257628D01*
X489958Y-260253D01*
X490176Y-262878D01*
X490831Y-265212D01*
X491704Y-266962D01*
X493014Y-268420D01*
X494761Y-269003D01*
X496507Y-268420D01*
X497818Y-266962D01*
X498691Y-265212D01*
X499346Y-262878D01*
X499564Y-260253D01*
X499346Y-257628D01*
X498691Y-255294D01*
X497818Y-253545D01*
X496507Y-252086D01*
X494761Y-251503D01*
G01X411644Y-224003D02*
Y-206503D01*
X416884D01*
X418631Y-207378D01*
X419941Y-209420D01*
X420378Y-211753D01*
X419941Y-214086D01*
X418849Y-215836D01*
X416884Y-216712D01*
X411644D01*
G01X438314Y-207962D02*
X437004Y-207086D01*
X435476Y-206503D01*
X433729D01*
X431764Y-207378D01*
X430236Y-208836D01*
X429144Y-210587D01*
X428271Y-213503D01*
X428052Y-216128D01*
X428489Y-218753D01*
X429144Y-220503D01*
X430454Y-222253D01*
X431983Y-223420D01*
X433511Y-224003D01*
X435039D01*
X436568Y-223420D01*
X437878Y-222545D01*
X438970Y-221379D01*
G01X452757Y-214670D02*
X453631Y-213795D01*
X454286Y-212337D01*
X454723Y-210294D01*
X454286Y-208545D01*
X453413Y-207378D01*
X451884Y-206503D01*
X445989D01*
Y-224003D01*
X453194D01*
X454723Y-222837D01*
X455596Y-221086D01*
X456033Y-219045D01*
X455596Y-217003D01*
X454286Y-215253D01*
X452757Y-214670D01*
X445989D01*
G01X461961Y-229836D02*
X475061D01*
G01X480989Y-224003D02*
Y-206503D01*
X491033Y-224003D01*
Y-206503D01*
G01X503511Y-224003D02*
X501764Y-223711D01*
X500236Y-222545D01*
X498926Y-220795D01*
X498052Y-218753D01*
X497616Y-216420D01*
Y-214086D01*
X498052Y-211753D01*
X498926Y-209711D01*
X500236Y-207962D01*
X501764Y-206795D01*
X503511Y-206503D01*
X505257Y-206795D01*
X506786Y-207962D01*
X508096Y-209711D01*
X508970Y-211753D01*
X509406Y-214086D01*
Y-216420D01*
X508970Y-218753D01*
X508096Y-220795D01*
X506786Y-222545D01*
X505257Y-223711D01*
X503511Y-224003D01*
G01X411819Y265945D02*
G03Y258071I0J-3937D01*
G01X460244Y-113228D02*
G03Y-105354I0J3937D01*
G01Y363425D02*
G03Y371299I0J3937D01*
G01X485441Y-105354D02*
G03Y-113228I0J-3937D01*
G01Y371299D02*
G03Y363425I0J-3937D01*
G01Y-113228D02*
X683652D01*
G01X485441Y371299D02*
X683652D01*
G01X514369Y0D02*
Y116437D01*
G01X535137Y0D02*
X514369D01*
G01Y116437D02*
G03X506494I-3937J0D01*
G01Y141634D02*
G03X514369I3937J0D01*
G01D02*
Y258071D01*
G01D02*
X535137D01*
G01Y-7874D02*
G03Y0I0J3937D01*
G01X551396Y69008D02*
G03X542813I-4291J0D01*
G03X551396I4291J0D01*
G01Y195351D02*
G03X542813Y195352I-4292J0D01*
G03X551396Y195351I4291J-1D01*
G01X535137Y258071D02*
G03Y265945I0J3937D01*
G01X554352Y-206503D02*
X559811Y-224003D01*
X565270Y-206503D01*
G01X581678Y-224003D02*
X572944D01*
Y-206503D01*
X581678D01*
G01X578184Y-214961D02*
X572944D01*
G01X590444Y-224003D02*
Y-206503D01*
X595903D01*
X597649Y-207378D01*
X598741Y-208545D01*
X599178Y-210878D01*
X598741Y-213212D01*
X597431Y-214670D01*
X595903Y-215545D01*
X590444D01*
G01X595903D02*
X599178Y-224003D01*
G01X612311Y-224586D02*
X611874Y-224295D01*
Y-223711D01*
X612311Y-223420D01*
X612748Y-223711D01*
Y-224295D01*
X612311Y-224586D01*
G01X560333Y0D02*
G03Y-7874I1J-3937D01*
G01X581102Y0D02*
X560333D01*
G01Y265945D02*
G03Y258071I1J-3937D01*
G01D02*
X581102D01*
G01X586061Y-269003D02*
Y-251503D01*
X583441Y-255003D01*
G01Y-269003D02*
X588681D01*
G01X581102Y116437D02*
Y0D01*
G01X588976Y116437D02*
G03X581102I-3937J0D01*
G01Y141634D02*
G03X588976I3937J0D01*
G01X581102Y258071D02*
Y141634D01*
G01X701011Y-251503D02*
Y-269003D01*
G01X695989Y-251503D02*
X706033D01*
G01X713926Y-266670D02*
X715673Y-268128D01*
X717638Y-269003D01*
X719384D01*
X721131Y-268128D01*
X722441Y-266670D01*
X723096Y-264628D01*
X722659Y-262587D01*
X721568Y-260836D01*
X719603Y-259670D01*
X716983Y-259086D01*
X715454Y-257920D01*
X714799Y-255878D01*
X715236Y-253836D01*
X716328Y-252378D01*
X717856Y-251503D01*
X719384D01*
X720913Y-252086D01*
X722223Y-253545D01*
G01X730334Y-269003D02*
Y-251503D01*
X736011Y-266086D01*
X741688Y-251503D01*
Y-269003D01*
G01X748708D02*
Y-251503D01*
X753074D01*
X754821Y-252378D01*
X756131Y-253545D01*
X757223Y-255294D01*
X758096Y-257337D01*
X758314Y-260253D01*
X758096Y-263170D01*
X757223Y-265212D01*
X756131Y-266962D01*
X754821Y-268128D01*
X753074Y-269003D01*
X748708D01*
G01X687894Y-206503D02*
Y-224003D01*
X696628D01*
G01X713691D02*
Y-212337D01*
G01Y-214378D02*
X712818Y-213212D01*
X711507Y-212628D01*
X709979Y-212337D01*
X708451Y-212920D01*
X707141Y-214086D01*
X706267Y-215836D01*
X705831Y-218170D01*
X706267Y-220503D01*
X707141Y-222253D01*
X708451Y-223420D01*
X709979Y-224003D01*
X711507Y-223711D01*
X712818Y-222837D01*
X713691Y-221670D01*
G01X722676Y-229253D02*
X723986Y-229836D01*
X725733Y-229253D01*
X726824Y-228087D01*
X727698Y-226628D01*
X729007Y-221962D01*
X731846Y-212337D01*
G01X724859D02*
X729007Y-221962D01*
G01X741486Y-216128D02*
X748473D01*
X747818Y-214086D01*
X746726Y-212920D01*
X745198Y-212337D01*
X743669Y-212628D01*
X742359Y-213503D01*
X741486Y-215545D01*
X741049Y-217295D01*
Y-219045D01*
X741486Y-220795D01*
X742578Y-222545D01*
X743888Y-223711D01*
X745416Y-224003D01*
X746944Y-223420D01*
X748473Y-221670D01*
G01X759204Y-224003D02*
Y-212337D01*
G01Y-214670D02*
X760296Y-213503D01*
X761388Y-212628D01*
X762916Y-212337D01*
X764007Y-212628D01*
X765318Y-213503D01*
G01X683652Y-113228D02*
G03Y-105354I0J3937D01*
G01Y-7874D02*
G03Y0I0J3937D01*
G01Y363425D02*
G03Y371299I0J3937D01*
G01X708848Y-113228D02*
X722440D01*
G01X708848Y-105354D02*
G03Y-113228I1J-3937D01*
G01Y0D02*
G03Y-7874I1J-3937D01*
G01Y371299D02*
X722440D01*
G01X708848D02*
G03Y363425I1J-3937D01*
G01X830008Y-224003D02*
Y-206503D01*
X834374D01*
X836121Y-207378D01*
X837431Y-208545D01*
X838523Y-210294D01*
X839396Y-212337D01*
X839614Y-215253D01*
X839396Y-218170D01*
X838523Y-220212D01*
X837431Y-221962D01*
X836121Y-223128D01*
X834374Y-224003D01*
X830008D01*
G01X849036Y-216128D02*
X856023D01*
X855368Y-214086D01*
X854276Y-212920D01*
X852748Y-212337D01*
X851219Y-212628D01*
X849909Y-213503D01*
X849036Y-215545D01*
X848599Y-217295D01*
Y-219045D01*
X849036Y-220795D01*
X850128Y-222545D01*
X851438Y-223711D01*
X852966Y-224003D01*
X854494Y-223420D01*
X856023Y-221670D01*
G01X866536Y-221962D02*
X867628Y-223128D01*
X869156Y-224003D01*
X870466D01*
X871776Y-223420D01*
X872649Y-222545D01*
X873086Y-221379D01*
X872868Y-219628D01*
X871994Y-218753D01*
X868064Y-217003D01*
X867191Y-214961D01*
X867628Y-213503D01*
X868501Y-212628D01*
X869811Y-212337D01*
X871121Y-212628D01*
X872431Y-213503D01*
G01X887311Y-212337D02*
Y-224003D01*
G01Y-207670D02*
X886874Y-207378D01*
Y-206795D01*
X887311Y-206503D01*
X887748Y-206795D01*
Y-207378D01*
X887311Y-207670D01*
G01X901754Y-228378D02*
X903283Y-229545D01*
X905029Y-229836D01*
X906557Y-229545D01*
X907868Y-228087D01*
X908741Y-226045D01*
Y-212337D01*
G01Y-214670D02*
X907868Y-213503D01*
X906557Y-212628D01*
X905029Y-212337D01*
X903283Y-212920D01*
X902191Y-214086D01*
X901317Y-216128D01*
X900881Y-218170D01*
X901099Y-219920D01*
X901973Y-221962D01*
X903283Y-223420D01*
X905029Y-224003D01*
X906339Y-223711D01*
X907868Y-222545D01*
X908741Y-221379D01*
G01X918599Y-224003D02*
Y-212337D01*
G01Y-215253D02*
X919473Y-213795D01*
X920783Y-212628D01*
X922529Y-212337D01*
X924057Y-212628D01*
X925368Y-213795D01*
X926023Y-215836D01*
Y-224003D01*
G01X936536Y-216128D02*
X943523D01*
X942868Y-214086D01*
X941776Y-212920D01*
X940248Y-212337D01*
X938719Y-212628D01*
X937409Y-213503D01*
X936536Y-215545D01*
X936099Y-217295D01*
Y-219045D01*
X936536Y-220795D01*
X937628Y-222545D01*
X938938Y-223711D01*
X940466Y-224003D01*
X941994Y-223420D01*
X943523Y-221670D01*
G01X954254Y-224003D02*
Y-212337D01*
G01Y-214670D02*
X955346Y-213503D01*
X956438Y-212628D01*
X957966Y-212337D01*
X959057Y-212628D01*
X960368Y-213503D01*
G01X874194Y-265503D02*
X875286Y-267253D01*
X876596Y-268420D01*
X878124Y-269003D01*
X879871Y-268420D01*
X881181Y-267253D01*
X882491Y-265503D01*
X882928Y-263170D01*
Y-251503D01*
G01X896061Y-269003D02*
X894314Y-268711D01*
X892786Y-267545D01*
X891476Y-265795D01*
X890602Y-263753D01*
X890166Y-261420D01*
Y-259086D01*
X890602Y-256753D01*
X891476Y-254711D01*
X892786Y-252962D01*
X894314Y-251795D01*
X896061Y-251503D01*
X897807Y-251795D01*
X899336Y-252962D01*
X900646Y-254711D01*
X901520Y-256753D01*
X901956Y-259086D01*
Y-261420D01*
X901520Y-263753D01*
X900646Y-265795D01*
X899336Y-267545D01*
X897807Y-268711D01*
X896061Y-269003D01*
G01X913561D02*
Y-261128D01*
X909194Y-251503D01*
G01X917928D02*
X913561Y-261128D01*
G01X1001011Y-269003D02*
Y-251503D01*
X998391Y-255003D01*
G01Y-269003D02*
X1003631D01*
G01X1014363Y-254420D02*
X1015673Y-252670D01*
X1017201Y-251795D01*
X1018948Y-251503D01*
X1021131Y-252086D01*
X1022659Y-253545D01*
X1023096Y-255294D01*
X1022878Y-257045D01*
X1022004Y-258503D01*
X1017638Y-261420D01*
X1015673Y-263461D01*
X1014363Y-266379D01*
X1013926Y-269003D01*
X1023096D01*
G01X1032081Y-269586D02*
X1039941Y-251503D01*
G01X1048708Y-265503D02*
X1050017Y-267545D01*
X1051764Y-268711D01*
X1053729Y-269003D01*
X1055476Y-268711D01*
X1057223Y-267253D01*
X1058314Y-265503D01*
X1058533Y-263753D01*
X1058096Y-261712D01*
X1056568Y-260253D01*
X1055039Y-259670D01*
X1053074D01*
G01X1055039D02*
X1056349Y-258795D01*
X1057441Y-257337D01*
X1057878Y-255587D01*
X1057441Y-253836D01*
X1056349Y-252378D01*
X1054384Y-251503D01*
X1052419Y-251795D01*
X1050454Y-252962D01*
G01X1071011Y-251503D02*
X1069264Y-252086D01*
X1067954Y-253545D01*
X1067081Y-255294D01*
X1066426Y-257628D01*
X1066208Y-260253D01*
X1066426Y-262878D01*
X1067081Y-265212D01*
X1067954Y-266962D01*
X1069264Y-268420D01*
X1071011Y-269003D01*
X1072757Y-268420D01*
X1074068Y-266962D01*
X1074941Y-265212D01*
X1075596Y-262878D01*
X1075814Y-260253D01*
X1075596Y-257628D01*
X1074941Y-255294D01*
X1074068Y-253545D01*
X1072757Y-252086D01*
X1071011Y-251503D01*
G01X1084581Y-269586D02*
X1092441Y-251503D01*
G01X1101863Y-254420D02*
X1103173Y-252670D01*
X1104701Y-251795D01*
X1106448Y-251503D01*
X1108631Y-252086D01*
X1110159Y-253545D01*
X1110596Y-255294D01*
X1110378Y-257045D01*
X1109504Y-258503D01*
X1105138Y-261420D01*
X1103173Y-263461D01*
X1101863Y-266379D01*
X1101426Y-269003D01*
X1110596D01*
G01X1123511Y-251503D02*
X1121764Y-252086D01*
X1120454Y-253545D01*
X1119581Y-255294D01*
X1118926Y-257628D01*
X1118708Y-260253D01*
X1118926Y-262878D01*
X1119581Y-265212D01*
X1120454Y-266962D01*
X1121764Y-268420D01*
X1123511Y-269003D01*
X1125257Y-268420D01*
X1126568Y-266962D01*
X1127441Y-265212D01*
X1128096Y-262878D01*
X1128314Y-260253D01*
X1128096Y-257628D01*
X1127441Y-255294D01*
X1126568Y-253545D01*
X1125257Y-252086D01*
X1123511Y-251503D01*
G01X1141011Y-269003D02*
Y-251503D01*
X1138391Y-255003D01*
G01Y-269003D02*
X1143631D01*
G01X1154363Y-261712D02*
X1155891Y-259670D01*
X1157201Y-258503D01*
X1158948Y-257920D01*
X1160476Y-258503D01*
X1161568Y-259670D01*
X1162441Y-261420D01*
X1162659Y-263461D01*
X1162441Y-265212D01*
X1161568Y-266962D01*
X1160257Y-268420D01*
X1158729Y-269003D01*
X1156983Y-268420D01*
X1155454Y-266670D01*
X1154581Y-264045D01*
X1154363Y-261128D01*
X1154799Y-257337D01*
X1155454Y-255294D01*
X1156546Y-253253D01*
X1158074Y-251795D01*
X1159603Y-251503D01*
X1161131Y-252086D01*
X1162223Y-253545D01*
G01X1048708Y-224003D02*
Y-206503D01*
X1053074D01*
X1054821Y-207378D01*
X1056131Y-208545D01*
X1057223Y-210294D01*
X1058096Y-212337D01*
X1058314Y-215253D01*
X1058096Y-218170D01*
X1057223Y-220212D01*
X1056131Y-221962D01*
X1054821Y-223128D01*
X1053074Y-224003D01*
X1048708D01*
G01X1074941D02*
Y-212337D01*
G01Y-214378D02*
X1074068Y-213212D01*
X1072757Y-212628D01*
X1071229Y-212337D01*
X1069701Y-212920D01*
X1068391Y-214086D01*
X1067517Y-215836D01*
X1067081Y-218170D01*
X1067517Y-220503D01*
X1068391Y-222253D01*
X1069701Y-223420D01*
X1071229Y-224003D01*
X1072757Y-223711D01*
X1074068Y-222837D01*
X1074941Y-221670D01*
G01X1088511Y-206503D02*
Y-224003D01*
G01X1085454Y-212337D02*
X1091568D01*
G01X1102736Y-216128D02*
X1109723D01*
X1109068Y-214086D01*
X1107976Y-212920D01*
X1106448Y-212337D01*
X1104919Y-212628D01*
X1103609Y-213503D01*
X1102736Y-215545D01*
X1102299Y-217295D01*
Y-219045D01*
X1102736Y-220795D01*
X1103828Y-222545D01*
X1105138Y-223711D01*
X1106666Y-224003D01*
X1108194Y-223420D01*
X1109723Y-221670D01*
G54D26*
X71500Y329389D03*
X165000Y308200D03*
X249000Y144200D03*
Y252700D03*
G54D35*
X139000Y312200D03*
Y319800D03*
Y329200D03*
Y336800D03*
X147000Y312200D03*
X155000D03*
X147000Y319800D03*
X155000D03*
Y329200D03*
Y336800D03*
X147000Y329200D03*
Y336800D03*
X163000Y329200D03*
Y336800D03*
X189500Y336200D03*
Y343800D03*
G54D17*
X67565Y309589D03*
X69530D03*
X71500D03*
Y321789D03*
X69530D03*
X67565D03*
X73470Y309589D03*
X75435D03*
Y321789D03*
X73470D03*
G54D44*
X213800Y292000D03*
G54D18*
X70800Y302689D03*
X59800Y325189D03*
X210900Y300200D03*
X237300Y67000D03*
Y75000D03*
Y71000D03*
Y122000D03*
Y126000D03*
Y138500D03*
Y130000D03*
Y134500D03*
Y175500D03*
Y183500D03*
Y179500D03*
Y238500D03*
Y243000D03*
Y230500D03*
Y234500D03*
Y247000D03*
G54D36*
X185811Y318500D03*
G54D27*
X71500Y332989D03*
X165000Y311800D03*
X249000Y147800D03*
Y256300D03*
G54D45*
X230410Y154660D03*
Y157220D03*
Y159780D03*
Y162340D03*
X246590D03*
Y159780D03*
Y157220D03*
Y154660D03*
G54D37*
X176168Y308657D03*
Y310626D03*
Y312594D03*
Y314563D03*
Y316531D03*
Y318500D03*
Y320469D03*
Y322437D03*
Y324406D03*
Y326374D03*
Y328343D03*
X195454Y310626D03*
Y308657D03*
Y326374D03*
Y324406D03*
Y322437D03*
Y320469D03*
Y318500D03*
Y316531D03*
Y314563D03*
Y312594D03*
Y328343D03*
G54D28*
X104955Y293900D03*
X102985D03*
X101015D03*
X99045D03*
Y303100D03*
X101015D03*
X102985D03*
X104955D03*
G54D46*
X256594Y68661D03*
Y70629D03*
Y72598D03*
Y74566D03*
Y84409D03*
Y86377D03*
Y88346D03*
Y90314D03*
Y92283D03*
Y94251D03*
Y96220D03*
Y98188D03*
Y100157D03*
Y102125D03*
Y104094D03*
Y106063D03*
Y108031D03*
Y110000D03*
Y111968D03*
Y113937D03*
Y115905D03*
Y117874D03*
Y119842D03*
Y121811D03*
Y123779D03*
Y125748D03*
Y127716D03*
Y129685D03*
Y131653D03*
Y133622D03*
Y135590D03*
Y137559D03*
Y139527D03*
Y177323D03*
Y179291D03*
Y181260D03*
Y183228D03*
Y193071D03*
Y195039D03*
Y197008D03*
Y198976D03*
Y200945D03*
Y202913D03*
Y204882D03*
Y206850D03*
Y208819D03*
Y210787D03*
Y212756D03*
Y214725D03*
Y216693D03*
Y218662D03*
Y220630D03*
Y222599D03*
Y224567D03*
Y226536D03*
Y228504D03*
Y230473D03*
Y232441D03*
Y234410D03*
Y236378D03*
Y238347D03*
Y240315D03*
Y242284D03*
Y244252D03*
Y246221D03*
Y248189D03*
X286319Y67677D03*
Y69645D03*
Y71614D03*
Y73582D03*
Y75551D03*
Y85393D03*
Y87362D03*
Y89330D03*
Y91299D03*
Y93267D03*
Y95236D03*
Y97204D03*
Y99173D03*
Y101141D03*
Y103110D03*
Y105078D03*
Y107047D03*
Y109015D03*
Y110984D03*
Y112952D03*
Y114921D03*
Y116889D03*
Y118858D03*
Y120826D03*
Y122795D03*
Y124763D03*
Y126732D03*
Y128700D03*
Y130669D03*
Y132637D03*
Y134606D03*
Y136574D03*
Y138543D03*
Y140511D03*
Y176339D03*
Y178307D03*
Y180276D03*
Y182244D03*
Y184213D03*
Y194055D03*
Y196024D03*
Y197992D03*
Y199961D03*
Y201929D03*
Y203898D03*
Y205866D03*
Y207835D03*
Y209803D03*
Y211772D03*
Y213740D03*
Y215709D03*
Y217677D03*
Y219646D03*
Y221614D03*
Y223583D03*
Y225551D03*
Y227520D03*
Y229488D03*
Y231457D03*
Y233425D03*
Y235394D03*
Y237362D03*
Y239331D03*
Y241299D03*
Y243268D03*
Y245236D03*
Y247205D03*
Y249173D03*
G54D19*
X63000Y303489D03*
X103000Y284300D03*
X100500Y342489D03*
X109500Y286800D03*
X130000Y295300D03*
X203600Y299800D03*
X290000Y163300D03*
G54D47*
X249000Y315100D03*
Y339900D03*
G54D29*
X100200Y310000D03*
G54D38*
X176311Y301700D03*
X294000Y154200D03*
X298000D03*
G54D39*
X176311Y298300D03*
X294000Y150800D03*
X298000D03*
G54D48*
X283268Y63346D03*
Y144842D03*
Y172008D03*
Y253504D03*
G54D49*
X297000Y118200D03*
M02*
